(kicad_pcb
	(version 20241229)
	(generator "pcbnew")
	(generator_version "9.0")
	(general
		(thickness 1.294)
		(legacy_teardrops no)
	)
	(paper "A3")
	(title_block
		(title "Kintex 410T devboard")
		(date "2024-04-03")
		(rev "1.1.2")
		(comment 9 "footprints 268-271 of 975")
	)
	(layers
		(0 "F.Cu" mixed)
		(4 "In1.Cu" power)
		(6 "In2.Cu" power)
		(8 "In3.Cu" mixed)
		(10 "In4.Cu" power)
		(12 "In5.Cu" mixed)
		(14 "In6.Cu" power)
		(16 "In7.Cu" mixed)
		(18 "In8.Cu" power)
		(2 "B.Cu" mixed)
		(9 "F.Adhes" user "F.Adhesive")
		(11 "B.Adhes" user "B.Adhesive")
		(13 "F.Paste" user)
		(15 "B.Paste" user)
		(5 "F.SilkS" user "F.Silkscreen")
		(7 "B.SilkS" user "B.Silkscreen")
		(1 "F.Mask" user)
		(3 "B.Mask" user)
		(17 "Dwgs.User" user "User.Drawings")
		(19 "Cmts.User" user "User.Comments")
		(21 "Eco1.User" user "User.Eco1")
		(23 "Eco2.User" user "User.Eco2")
		(25 "Edge.Cuts" user)
		(27 "Margin" user)
		(31 "F.CrtYd" user "F.Courtyard")
		(29 "B.CrtYd" user "B.Courtyard")
		(35 "F.Fab" user)
		(33 "B.Fab" user)
	)
	(footprint "antmicro-footprints:TSSOP-20_W4.4mm"
		(layer "F.Cu")
		(at 224.2 139.3 90)
		(descr "http://www.ti.com/lit/ds/symlink/txb0108.pdf")
		(property "Reference" "U42"
			(at -4.25 -1.1 180)
			(layer "F.SilkS")
			(effects
				(font
					(size 0.7 0.7)
					(thickness 0.15)
				)
				(justify left bottom)
			)
		)
		(property "Value" "CDCE906PWR"
			(at -5.33 4.57 90)
			(layer "F.Fab")
			(effects
				(font
					(size 0.7 0.7)
					(thickness 0.15)
				)
				(justify left bottom)
			)
		)
		(property "Description" "Clock generator/frequency synthesizer (PLL)"
			(at 0 0 90)
			(layer "F.Fab")
			(hide yes)
			(effects
				(font
					(size 1.27 1.27)
					(thickness 0.15)
				)
			)
		)
		(property "Author" "Antmicro"
			(at 363.5 -84.9 0)
			(layer "F.Fab")
			(hide yes)
			(effects
				(font
					(size 1 1)
					(thickness 0.15)
				)
			)
		)
		(property "License" "Apache-2.0"
			(at 363.5 -84.9 0)
			(layer "F.Fab")
			(hide yes)
			(effects
				(font
					(size 1 1)
					(thickness 0.15)
				)
			)
		)
		(property "MPN" "CDCE906PWR"
			(at 363.5 -84.9 0)
			(layer "F.Fab")
			(hide yes)
			(effects
				(font
					(size 1 1)
					(thickness 0.15)
				)
			)
		)
		(property "Manufacturer" "Texas Instruments"
			(at 363.5 -84.9 0)
			(layer "F.Fab")
			(hide yes)
			(effects
				(font
					(size 1 1)
					(thickness 0.15)
				)
			)
		)
		(sheetname "Clocks")
		(sheetfile "clocks.kicad_sch")
		(attr smd)
		(fp_line
			(start 3.499 -2.4)
			(end 3.499 -2.101)
			(stroke
				(width 0.15)
				(type solid)
			)
			(layer "F.SilkS")
		)
		(fp_line
			(start 3.2 -2.4)
			(end 3.499 -2.4)
			(stroke
				(width 0.15)
				(type solid)
			)
			(layer "F.SilkS")
		)
		(fp_line
			(start -3.202 -2.4)
			(end -3.5 -2.4)
			(stroke
				(width 0.15)
				(type solid)
			)
			(layer "F.SilkS")
		)
		(fp_line
			(start -3.5 -2.4)
			(end -3.5 -2.101)
			(stroke
				(width 0.15)
				(type solid)
			)
			(layer "F.SilkS")
		)
		(fp_line
			(start -3.49 1.825)
			(end -3.49 2.215)
			(stroke
				(width 0.15)
				(type solid)
			)
			(layer "F.SilkS")
		)
		(fp_line
			(start -3.49 2.215)
			(end -3.28 2.425)
			(stroke
				(width 0.15)
				(type solid)
			)
			(layer "F.SilkS")
		)
		(fp_line
			(start 3.499 2.398)
			(end 3.499 2.1)
			(stroke
				(width 0.15)
				(type solid)
			)
			(layer "F.SilkS")
		)
		(fp_line
			(start 3.499 2.398)
			(end 3.2 2.398)
			(stroke
				(width 0.15)
				(type solid)
			)
			(layer "F.SilkS")
		)
		(fp_line
			(start -3.28 2.815)
			(end -3.28 2.425)
			(stroke
				(width 0.15)
				(type solid)
			)
			(layer "F.SilkS")
		)
		(fp_circle
			(center -3.41 3.34)
			(end -3.36 3.34)
			(stroke
				(width 0.15)
				(type solid)
			)
			(fill yes)
			(layer "F.SilkS")
		)
		(fp_rect
			(start -3.75 -3.709)
			(end 3.749 3.706)
			(stroke
				(width 0.05)
				(type solid)
			)
			(fill no)
			(layer "F.CrtYd")
		)
		(fp_line
			(start 3.249 -2.202)
			(end 3.249 2.2)
			(stroke
				(width 0.15)
				(type solid)
			)
			(layer "F.Fab")
		)
		(fp_line
			(start -3.25 -2.202)
			(end 3.249 -2.202)
			(stroke
				(width 0.15)
				(type solid)
			)
			(layer "F.Fab")
		)
		(fp_line
			(start -3.25 -2.202)
			(end -3.25 1.729)
			(stroke
				(width 0.15)
				(type solid)
			)
			(layer "F.Fab")
		)
		(fp_line
			(start -3.242 1.739)
			(end -2.742 2.2)
			(stroke
				(width 0.15)
				(type solid)
			)
			(layer "F.Fab")
		)
		(fp_line
			(start 3.249 2.2)
			(end -2.73 2.2)
			(stroke
				(width 0.15)
				(type solid)
			)
			(layer "F.Fab")
		)
		(pad "1" smd rect
			(at -2.926 2.797 90)
			(size 0.3 1.6)
			(layers "F.Cu" "F.Mask" "F.Paste")
			(net 1387 "/SUP_MCU.PG_3V3")
			(pinfunction "S0/A0/CLK_SEL")
			(pintype "input")
			(solder_mask_margin 0.07)
		)
		(pad "2" smd rect
			(at -2.275 2.797 90)
			(size 0.3 1.6)
			(layers "F.Cu" "F.Mask" "F.Paste")
			(net 1407 "unconnected-(U42-S1{slash}A1-Pad2)")
			(pinfunction "S1/A1")
			(pintype "input+no_connect")
			(solder_mask_margin 0.07)
		)
		(pad "3" smd rect
			(at -1.625 2.797 90)
			(size 0.3 1.6)
			(layers "F.Cu" "F.Mask" "F.Paste")
			(net 1231 "Net-(C366-Pad2)")
			(pinfunction "VCC")
			(pintype "power_in")
			(solder_mask_margin 0.07)
		)
		(pad "4" smd rect
			(at -0.975 2.797 90)
			(size 0.3 1.6)
			(layers "F.Cu" "F.Mask" "F.Paste")
			(net 1 "GND")
			(pinfunction "GND")
			(pintype "passive")
			(solder_mask_margin 0.07)
		)
		(pad "5" smd rect
			(at -0.328 2.797 90)
			(size 0.3 1.6)
			(layers "F.Cu" "F.Mask" "F.Paste")
			(net 752 "/Clocks/PLL_XI")
			(pinfunction "CLK_IN0")
			(pintype "input")
			(solder_mask_margin 0.07)
		)
		(pad "6" smd rect
			(at 0.325 2.797 90)
			(size 0.3 1.6)
			(layers "F.Cu" "F.Mask" "F.Paste")
			(net 753 "/Clocks/PLL_XO")
			(pinfunction "CLK_IN1")
			(pintype "input")
			(solder_mask_margin 0.07)
		)
		(pad "7" smd rect
			(at 0.972 2.797 90)
			(size 0.3 1.6)
			(layers "F.Cu" "F.Mask" "F.Paste")
			(net 1231 "Net-(C366-Pad2)")
			(pinfunction "VCC")
			(pintype "passive")
			(solder_mask_margin 0.07)
		)
		(pad "8" smd rect
			(at 1.624 2.797 90)
			(size 0.3 1.6)
			(layers "F.Cu" "F.Mask" "F.Paste")
			(net 1 "GND")
			(pinfunction "GND")
			(pintype "passive")
			(solder_mask_margin 0.07)
		)
		(pad "9" smd rect
			(at 2.273 2.797 90)
			(size 0.3 1.6)
			(layers "F.Cu" "F.Mask" "F.Paste")
			(net 1336 "/I2C.SDA")
			(pinfunction "SDA")
			(pintype "bidirectional")
			(solder_mask_margin 0.07)
		)
		(pad "10" smd rect
			(at 2.922 2.797 90)
			(size 0.3 1.6)
			(layers "F.Cu" "F.Mask" "F.Paste")
			(net 1338 "/I2C.SCL")
			(pinfunction "SCK")
			(pintype "bidirectional")
			(solder_mask_margin 0.07)
		)
		(pad "11" smd rect
			(at 2.922 -2.801 90)
			(size 0.3 1.6)
			(layers "F.Cu" "F.Mask" "F.Paste")
			(net 971 "/Clocks/PLL_Y0")
			(pinfunction "Y0")
			(pintype "tri_state")
			(solder_mask_margin 0.07)
		)
		(pad "12" smd rect
			(at 2.273 -2.801 90)
			(size 0.3 1.6)
			(layers "F.Cu" "F.Mask" "F.Paste")
			(net 972 "/Clocks/PLL_Y1")
			(pinfunction "Y1")
			(pintype "tri_state")
			(solder_mask_margin 0.07)
		)
		(pad "13" smd rect
			(at 1.624 -2.801 90)
			(size 0.3 1.6)
			(layers "F.Cu" "F.Mask" "F.Paste")
			(net 1 "GND")
			(pinfunction "GND")
			(pintype "passive")
			(solder_mask_margin 0.07)
		)
		(pad "14" smd rect
			(at 0.972 -2.801 90)
			(size 0.3 1.6)
			(layers "F.Cu" "F.Mask" "F.Paste")
			(net 24 "+3V3")
			(pinfunction "VCCOUT1")
			(pintype "power_in")
			(solder_mask_margin 0.07)
		)
		(pad "15" smd rect
			(at 0.325 -2.801 90)
			(size 0.3 1.6)
			(layers "F.Cu" "F.Mask" "F.Paste")
			(net 1408 "unconnected-(U42-Y2-Pad15)")
			(pinfunction "Y2")
			(pintype "tri_state+no_connect")
			(solder_mask_margin 0.07)
		)
		(pad "16" smd rect
			(at -0.328 -2.801 90)
			(size 0.3 1.6)
			(layers "F.Cu" "F.Mask" "F.Paste")
			(net 1409 "unconnected-(U42-Y3-Pad16)")
			(pinfunction "Y3")
			(pintype "tri_state+no_connect")
			(solder_mask_margin 0.07)
		)
		(pad "17" smd rect
			(at -0.975 -2.801 90)
			(size 0.3 1.6)
			(layers "F.Cu" "F.Mask" "F.Paste")
			(net 1 "GND")
			(pinfunction "GND")
			(pintype "passive")
			(solder_mask_margin 0.07)
		)
		(pad "18" smd rect
			(at -1.625 -2.801 90)
			(size 0.3 1.6)
			(layers "F.Cu" "F.Mask" "F.Paste")
			(net 24 "+3V3")
			(pinfunction "VCCOUT2")
			(pintype "power_in")
			(solder_mask_margin 0.07)
		)
		(pad "19" smd rect
			(at -2.275 -2.801 90)
			(size 0.3 1.6)
			(layers "F.Cu" "F.Mask" "F.Paste")
			(net 973 "/Clocks/PLL_Y4")
			(pinfunction "Y4")
			(pintype "tri_state")
			(solder_mask_margin 0.07)
		)
		(pad "20" smd rect
			(at -2.926 -2.801 90)
			(size 0.3 1.6)
			(layers "F.Cu" "F.Mask" "F.Paste")
			(net 1410 "unconnected-(U42-Y5-Pad20)")
			(pinfunction "Y5")
			(pintype "tri_state+no_connect")
			(solder_mask_margin 0.07)
		)
	)
	(footprint "antmicro-footprints:C_0603_1608Metric"
		(layer "F.Cu")
		(at 160.55 165.55)
		(descr "Capacitor SMD 0603")
		(tags "capacitor 0603")
		(property "Reference" "C323"
			(at 0.95 0.4 0)
			(layer "F.SilkS")
			(effects
				(font
					(size 0.7 0.7)
					(thickness 0.15)
				)
				(justify left bottom)
			)
		)
		(property "Value" "C_22u_0603"
			(at 0 1.6 0)
			(layer "F.Fab")
			(effects
				(font
					(size 0.7 0.7)
					(thickness 0.15)
				)
				(justify left bottom)
			)
		)
		(property "Description" "SMD Multilayer Ceramic Capacitor, 22 µF, 6.3 V, 0603 [1608 Metric], ± 20%, X5R, GRM Series"
			(at 0 0 0)
			(layer "F.Fab")
			(hide yes)
			(effects
				(font
					(size 1.27 1.27)
					(thickness 0.15)
				)
			)
		)
		(property "Author" "Antmicro"
			(at 0 0 0)
			(layer "F.Fab")
			(hide yes)
			(effects
				(font
					(size 1 1)
					(thickness 0.15)
				)
			)
		)
		(property "Dielectric" ""
			(at 0 0 0)
			(layer "F.Fab")
			(hide yes)
			(effects
				(font
					(size 1 1)
					(thickness 0.15)
				)
			)
		)
		(property "License" "Apache-2.0"
			(at 0 0 0)
			(layer "F.Fab")
			(hide yes)
			(effects
				(font
					(size 1 1)
					(thickness 0.15)
				)
			)
		)
		(property "MPN" "GRM188R60J226MEA0D"
			(at 0 0 0)
			(layer "F.Fab")
			(hide yes)
			(effects
				(font
					(size 1 1)
					(thickness 0.15)
				)
			)
		)
		(property "Manufacturer" "Murata"
			(at 0 0 0)
			(layer "F.Fab")
			(hide yes)
			(effects
				(font
					(size 1 1)
					(thickness 0.15)
				)
			)
		)
		(property "Val" "22u"
			(at 0 0 0)
			(layer "F.Fab")
			(hide yes)
			(effects
				(font
					(size 1 1)
					(thickness 0.15)
				)
			)
		)
		(property "Voltage" ""
			(at 0 0 0)
			(layer "F.Fab")
			(hide yes)
			(effects
				(font
					(size 1 1)
					(thickness 0.15)
				)
			)
		)
		(sheetname "DC-DC Converters")
		(sheetfile "dc-dc.kicad_sch")
		(attr smd)
		(fp_line
			(start -0.15 -0.4)
			(end 0.15 -0.4)
			(stroke
				(width 0.15)
				(type solid)
			)
			(layer "F.SilkS")
		)
		(fp_line
			(start -0.15 0.4)
			(end 0.15 0.4)
			(stroke
				(width 0.15)
				(type solid)
			)
			(layer "F.SilkS")
		)
		(fp_rect
			(start -1.25 -0.65)
			(end 1.25 0.65)
			(stroke
				(width 0.05)
				(type solid)
			)
			(fill no)
			(layer "F.CrtYd")
		)
		(fp_rect
			(start -0.8 -0.4)
			(end 0.8 0.4)
			(stroke
				(width 0.15)
				(type solid)
			)
			(fill no)
			(layer "F.Fab")
		)
		(pad "1" smd roundrect
			(at -0.7 0)
			(size 0.8 1)
			(layers "F.Cu" "F.Mask" "F.Paste")
			(roundrect_rratio 0.2)
			(net 1 "GND")
			(pintype "passive")
		)
		(pad "2" smd roundrect
			(at 0.7 0)
			(size 0.8 1)
			(layers "F.Cu" "F.Mask" "F.Paste")
			(roundrect_rratio 0.2)
			(net 734 "/DC-DC Converters/1V8_local")
			(pintype "passive")
		)
	)
	(footprint "antmicro-footprints:TSOT23-6"
		(layer "F.Cu")
		(at 252.999 98.5 180)
		(property "Reference" "U30"
			(at -2.951 1.15 90)
			(layer "F.SilkS")
			(effects
				(font
					(size 0.7 0.7)
					(thickness 0.15)
				)
				(justify right bottom)
			)
		)
		(property "Value" "AP22615A_TSOT26"
			(at 0 2.6 0)
			(layer "F.Fab")
			(effects
				(font
					(size 0.7 0.7)
					(thickness 0.15)
				)
				(justify right bottom)
			)
		)
		(property "Description" "Power Load Distribution Switch, High Side, Active High, 1 Output, 5.5 V, 3.6 A, 0.04 ohm, TSOT-26-6"
			(at 0 0 180)
			(layer "F.Fab")
			(hide yes)
			(effects
				(font
					(size 1.27 1.27)
					(thickness 0.15)
				)
			)
		)
		(property "Author" "Antmicro"
			(at 505.998 197 0)
			(layer "F.Fab")
			(hide yes)
			(effects
				(font
					(size 1 1)
					(thickness 0.15)
				)
			)
		)
		(property "License" "Apache-2.0"
			(at 505.998 197 0)
			(layer "F.Fab")
			(hide yes)
			(effects
				(font
					(size 1 1)
					(thickness 0.15)
				)
			)
		)
		(property "MPN" "AP22615AWU-7"
			(at 505.998 197 0)
			(layer "F.Fab")
			(hide yes)
			(effects
				(font
					(size 1 1)
					(thickness 0.15)
				)
			)
		)
		(property "Manufacturer" "Diodes Incorporated"
			(at 505.998 197 0)
			(layer "F.Fab")
			(hide yes)
			(effects
				(font
					(size 1 1)
					(thickness 0.15)
				)
			)
		)
		(sheetname "USB PHY")
		(sheetfile "usb-phy.kicad_sch")
		(attr smd)
		(fp_line
			(start 1 1.55)
			(end 1 1.4)
			(stroke
				(width 0.15)
				(type solid)
			)
			(layer "F.SilkS")
		)
		(fp_line
			(start 1 1.55)
			(end -1 1.55)
			(stroke
				(width 0.15)
				(type solid)
			)
			(layer "F.SilkS")
		)
		(fp_line
			(start 1 -1.497)
			(end 1 -1.375)
			(stroke
				(width 0.15)
				(type solid)
			)
			(layer "F.SilkS")
		)
		(fp_line
			(start 1 -1.497)
			(end -1 -1.5)
			(stroke
				(width 0.15)
				(type solid)
			)
			(layer "F.SilkS")
		)
		(fp_line
			(start -1 1.55)
			(end -1 1.4)
			(stroke
				(width 0.15)
				(type solid)
			)
			(layer "F.SilkS")
		)
		(fp_line
			(start -1 -1.5)
			(end -1 -1.375)
			(stroke
				(width 0.15)
				(type solid)
			)
			(layer "F.SilkS")
		)
		(fp_circle
			(center -1.44 -1.5)
			(end -1.39 -1.5)
			(stroke
				(width 0.15)
				(type solid)
			)
			(fill yes)
			(layer "F.SilkS")
		)
		(fp_rect
			(start 1.93 -1.7)
			(end -1.93 1.7)
			(stroke
				(width 0.05)
				(type solid)
			)
			(fill no)
			(layer "F.CrtYd")
		)
		(fp_line
			(start -0.45 -1.521)
			(end -0.876 -1.096)
			(stroke
				(width 0.15)
				(type solid)
			)
			(layer "F.Fab")
		)
		(fp_rect
			(start 0.875 1.528)
			(end -0.875 -1.525)
			(stroke
				(width 0.15)
				(type solid)
			)
			(fill no)
			(layer "F.Fab")
		)
		(pad "1" smd rect
			(at -1.301 -0.947 90)
			(size 0.7 1.2)
			(layers "F.Cu" "F.Mask" "F.Paste")
			(net 705 "/USB PHY/USB_HOST_VBUS")
			(pinfunction "OUT")
			(pintype "power_out")
		)
		(pad "2" smd rect
			(at -1.301 0.004 90)
			(size 0.7 1.2)
			(layers "F.Cu" "F.Mask" "F.Paste")
			(net 1 "GND")
			(pinfunction "GND")
			(pintype "power_in")
		)
		(pad "3" smd rect
			(at -1.301 0.954 90)
			(size 0.7 1.2)
			(layers "F.Cu" "F.Mask" "F.Paste")
			(net 637 "/USB PHY/USB_HOST_VBUS_FLG")
			(pinfunction "FLG")
			(pintype "output")
		)
		(pad "4" smd rect
			(at 1.299 0.954 90)
			(size 0.7 1.2)
			(layers "F.Cu" "F.Mask" "F.Paste")
			(net 583 "/USB PHY/USB_HOST_VBUS_EN")
			(pinfunction "EN")
			(pintype "input")
		)
		(pad "5" smd rect
			(at 1.299 0.004 90)
			(size 0.7 1.2)
			(layers "F.Cu" "F.Mask" "F.Paste")
			(net 382 "Net-(U30-ISET)")
			(pinfunction "ISET")
			(pintype "passive")
		)
		(pad "6" smd rect
			(at 1.299 -0.947 90)
			(size 0.7 1.2)
			(layers "F.Cu" "F.Mask" "F.Paste")
			(net 703 "+5V")
			(pinfunction "IN")
			(pintype "power_in")
		)
	)
	(footprint "antmicro-footprints:C_0402_1005Metric"
		(layer "F.Cu")
		(at 220.8 158.95 180)
		(descr "Capacitor SMD 0402")
		(tags "capacitor SMD 0402")
		(property "Reference" "C165"
			(at 0.75 0.55 0)
			(layer "F.SilkS")
			(effects
				(font
					(size 0.7 0.7)
					(thickness 0.15)
				)
				(justify right bottom)
			)
		)
		(property "Value" "C_2n2_0402"
			(at 0 1.4 0)
			(layer "F.Fab")
			(effects
				(font
					(size 0.7 0.7)
					(thickness 0.15)
				)
				(justify right bottom)
			)
		)
		(property "Description" "SMD Multilayer Ceramic Capacitor, 2200 pF, 50 V, 0402 [1005 Metric], ± 5%, X7R, C Series KEMET"
			(at 0 0 180)
			(layer "F.Fab")
			(hide yes)
			(effects
				(font
					(size 1.27 1.27)
					(thickness 0.15)
				)
			)
		)
		(property "Author" "Antmicro"
			(at 441.6 317.9 0)
			(layer "F.Fab")
			(hide yes)
			(effects
				(font
					(size 1 1)
					(thickness 0.15)
				)
			)
		)
		(property "Dielectric" ""
			(at 441.6 317.9 0)
			(layer "F.Fab")
			(hide yes)
			(effects
				(font
					(size 1 1)
					(thickness 0.15)
				)
			)
		)
		(property "License" "Apache-2.0"
			(at 441.6 317.9 0)
			(layer "F.Fab")
			(hide yes)
			(effects
				(font
					(size 1 1)
					(thickness 0.15)
				)
			)
		)
		(property "MPN" "C0402C222J5RACTU"
			(at 441.6 317.9 0)
			(layer "F.Fab")
			(hide yes)
			(effects
				(font
					(size 1 1)
					(thickness 0.15)
				)
			)
		)
		(property "Manufacturer" "KEMET"
			(at 441.6 317.9 0)
			(layer "F.Fab")
			(hide yes)
			(effects
				(font
					(size 1 1)
					(thickness 0.15)
				)
			)
		)
		(property "Val" "2n2"
			(at 441.6 317.9 0)
			(layer "F.Fab")
			(hide yes)
			(effects
				(font
					(size 1 1)
					(thickness 0.15)
				)
			)
		)
		(property "Voltage" ""
			(at 441.6 317.9 0)
			(layer "F.Fab")
			(hide yes)
			(effects
				(font
					(size 1 1)
					(thickness 0.15)
				)
			)
		)
		(sheetname "FPGA Config")
		(sheetfile "fpga-config.kicad_sch")
		(attr smd)
		(fp_rect
			(start -0.925 -0.47)
			(end 0.925 0.47)
			(stroke
				(width 0.05)
				(type default)
			)
			(fill no)
			(layer "F.CrtYd")
		)
		(fp_line
			(start 0.504 0.248)
			(end -0.494 0.248)
			(stroke
				(width 0.15)
				(type solid)
			)
			(layer "F.Fab")
		)
		(fp_line
			(start 0.504 -0.25)
			(end 0.504 0.248)
			(stroke
				(width 0.15)
				(type solid)
			)
			(layer "F.Fab")
		)
		(fp_line
			(start -0.494 0.248)
			(end -0.494 -0.25)
			(stroke
				(width 0.15)
				(type solid)
			)
			(layer "F.Fab")
		)
		(fp_line
			(start -0.494 -0.25)
			(end 0.504 -0.25)
			(stroke
				(width 0.15)
				(type solid)
			)
			(layer "F.Fab")
		)
		(pad "1" smd roundrect
			(at -0.48 0 180)
			(size 0.59 0.64)
			(layers "F.Cu" "F.Mask" "F.Paste")
			(roundrect_rratio 0.25)
			(net 9 "/FPGA Config/FPGA_CFG_DXN")
			(pintype "passive")
		)
		(pad "2" smd roundrect
			(at 0.48 0 180)
			(size 0.59 0.64)
			(layers "F.Cu" "F.Mask" "F.Paste")
			(roundrect_rratio 0.25)
			(net 10 "/FPGA Config/FPGA_CFG_DXP")
			(pintype "passive")
		)
	)
)
